# TIMECARD (Time Appliance Project (Time Card)) — schematic netlist excerpt (pin names and nets, part order shuffled) for the footprints in the layout excerpt that follows; sources: Cadence DE-HDL packaged netlist, KiCad conversion of R4006-B0001-02_R01.brd

R111  RESISTOR  33OHM 1%  pkg SMC_0402R_H016  page 22 : \1\ = FPGA_IN_GPSTP2_OUT ; \2\ = GPSTP2_OUT
R295  RESISTOR  10KOHM 1%  pkg SMC_0402R_H016  page 31 : \1\ = XP3R3V_FPGA ; \2\ = UNNAMED_515_NCP45560IMNTWGHDFN1

(kicad_pcb
	(version 20260206)
	(generator "pcbnew")
	(generator_version "10.0")
	(general
		(thickness 1.6)
		(legacy_teardrops no)
	)
	(paper "A4")
	(title_block
		(title "timecard-production-celestica-r4006 — R4006-B0001-02_R01.brd")
		(comment 1 "Time Appliance Project (Time Card) / footprints 926-927 of 1113")
	)
	(layers
		(0 "F.Cu" signal "TOP")
		(4 "In1.Cu" signal "L02_GND1")
		(6 "In2.Cu" signal "L03_SIG1")
		(8 "In3.Cu" signal "L04_GND2")
		(10 "In4.Cu" signal "L05_VCC1")
		(12 "In5.Cu" signal "L06_VCC2")
		(14 "In6.Cu" signal "L07_GND3")
		(16 "In7.Cu" signal "L08_SIG2")
		(18 "In8.Cu" signal "L09_GND4")
		(2 "B.Cu" signal "BOTTOM")
		(9 "F.Adhes" user "F.Adhesive")
		(11 "B.Adhes" user "B.Adhesive")
		(13 "F.Paste" user "Package Geometry/Pastemask Top")
		(15 "B.Paste" user "Package Geometry/Pastemask Bottom")
		(5 "F.SilkS" user "Ref Des/Silkscreen Top")
		(7 "B.SilkS" user "Ref Des/Silkscreen Bottom")
		(1 "F.Mask" user "Board Geometry/Soldermask Top")
		(3 "B.Mask" user "Board Geometry/Soldermask Bottom")
		(17 "Dwgs.User" user "User.Drawings")
		(19 "Cmts.User" user "User.Comments")
		(21 "Eco1.User" user "User.Eco1")
		(23 "Eco2.User" user "User.Eco2")
		(25 "Edge.Cuts" user "Board Geometry/Outline")
		(27 "Margin" user)
		(31 "F.CrtYd" user "Package Geometry/Place Bound Top")
		(29 "B.CrtYd" user "Package Geometry/Place Bound Bottom")
		(35 "F.Fab" user "Ref Des/Assembly Top")
		(33 "B.Fab" user "Ref Des/Assembly Bottom")
	)
	(footprint ""
		(layer "B.Cu")
		(at 110.363 -75.565 180)
		(property "Reference" "R295"
			(at 2.032 1.35763 0)
			(unlocked yes)
			(layer "B.SilkS")
			(effects
				(font
					(size 0.7874 0.5842)
					(thickness 0.1524)
				)
				(justify mirror)
			)
		)
		(property "Value" "VAL*"
			(at -0.02032 2.13233 180)
			(unlocked yes)
			(layer "B.Fab")
			(hide yes)
			(effects
				(font
					(size 0.7874 0.5842)
					(thickness 0.1524)
				)
				(justify mirror)
			)
		)
		(property "Tolerance" "TOL*"
			(at -0.044704 3.05435 180)
			(unlocked yes)
			(layer "Cmts.User")
			(hide yes)
			(effects
				(font
					(size 0.7874 0.5842)
					(thickness 0.1524)
				)
				(justify mirror)
			)
		)
		(property "User Part Number" "PARTNUM*"
			(at -0.02032 4.024884 180)
			(unlocked yes)
			(layer "Cmts.User")
			(hide yes)
			(effects
				(font
					(size 0.7874 0.5842)
					(thickness 0.1524)
				)
				(justify mirror)
			)
		)
		(property "Device Type" "RESISTOR-G155-11002-01,10KOHM,A"
			(at -0.008382 1.210564 180)
			(unlocked yes)
			(layer "B.Fab")
			(hide yes)
			(effects
				(font
					(size 0.7874 0.5842)
					(thickness 0.1524)
				)
				(justify mirror)
			)
		)
		(duplicate_pad_numbers_are_jumpers no)
		(fp_line
			(start 1.143 0.5588)
			(end -1.143 0.5588)
			(stroke
				(width 0.1)
				(type default)
			)
			(layer "B.SilkS")
		)
		(fp_line
			(start 1.143 -0.5588)
			(end 1.143 0.5588)
			(stroke
				(width 0.1)
				(type default)
			)
			(layer "B.SilkS")
		)
		(fp_line
			(start -1.143 0.5588)
			(end -1.143 -0.5588)
			(stroke
				(width 0.1)
				(type default)
			)
			(layer "B.SilkS")
		)
		(fp_line
			(start -1.143 -0.5588)
			(end 1.143 -0.5588)
			(stroke
				(width 0.1)
				(type default)
			)
			(layer "B.SilkS")
		)
		(fp_poly
			(pts
				(xy 1.143 0.5588) (xy -1.143 0.5588) (xy -1.143 -0.5588) (xy 1.143 -0.5588)
			)
			(stroke
				(width 0)
				(type default)
			)
			(fill no)
			(layer "B.CrtYd")
		)
		(fp_line
			(start 0.508 0.3048)
			(end -0.508 0.3048)
			(stroke
				(width 0.1)
				(type default)
			)
			(layer "B.Fab")
		)
		(fp_line
			(start 0.508 -0.3048)
			(end 0.508 0.3048)
			(stroke
				(width 0.1)
				(type default)
			)
			(layer "B.Fab")
		)
		(fp_line
			(start -0.508 0.3048)
			(end -0.508 -0.3048)
			(stroke
				(width 0.1)
				(type default)
			)
			(layer "B.Fab")
		)
		(fp_line
			(start -0.508 -0.3048)
			(end 0.508 -0.3048)
			(stroke
				(width 0.1)
				(type default)
			)
			(layer "B.Fab")
		)
		(pad "1" smd rect
			(at 0.5334 0)
			(size 0.7112 0.6096)
			(layers "B.Cu" "B.Mask" "B.Paste")
			(net "XP3R3V_FPGA")
		)
		(pad "2" smd rect
			(at -0.5334 0)
			(size 0.7112 0.6096)
			(layers "B.Cu" "B.Mask" "B.Paste")
			(net "UNNAMED_515_NCP45560IMNTWGHDFN1")
		)
		(zone
			(layer "B.Cu")
			(hatch none 0.5)
			(connect_pads
				(clearance 0)
			)
			(min_thickness 0.25)
			(keepout
				(tracks allowed)
				(vias not_allowed)
				(pads allowed)
				(copperpour not_allowed)
				(footprints allowed)
			)
			(placement
				(enabled no)
				(sheetname "")
			)
			(fill
				(thermal_gap 0.5)
				(thermal_bridge_width 0.5)
				(island_removal_mode 0)
			)
			(polygon
				(pts
					(xy 110.2868 -75.8698) (xy 110.2868 -75.2602) (xy 110.4392 -75.2602) (xy 110.4392 -75.8698)
				)
			)
		)
		(zone
			(layer "B.Cu")
			(hatch none 0.5)
			(connect_pads
				(clearance 0)
			)
			(min_thickness 0.25)
			(keepout
				(tracks not_allowed)
				(vias allowed)
				(pads allowed)
				(copperpour not_allowed)
				(footprints allowed)
			)
			(placement
				(enabled no)
				(sheetname "")
			)
			(fill
				(thermal_gap 0.5)
				(thermal_bridge_width 0.5)
				(island_removal_mode 0)
			)
			(polygon
				(pts
					(xy 110.2868 -75.8698) (xy 110.2868 -75.2602) (xy 110.4392 -75.2602) (xy 110.4392 -75.8698)
				)
			)
		)
	)
	(footprint ""
		(layer "B.Cu")
		(at 124.079 -89.535 -90)
		(property "Reference" "R111"
			(at -3.683 -0.08763 270)
			(unlocked yes)
			(layer "B.SilkS")
			(effects
				(font
					(size 0.7874 0.5842)
					(thickness 0.1524)
				)
				(justify mirror)
			)
		)
		(property "Value" "VAL*"
			(at -0.02032 2.13233 270)
			(unlocked yes)
			(layer "B.Fab")
			(hide yes)
			(effects
				(font
					(size 0.7874 0.5842)
					(thickness 0.1524)
				)
				(justify mirror)
			)
		)
		(property "Tolerance" "TOL*"
			(at -0.044704 3.05435 270)
			(unlocked yes)
			(layer "Cmts.User")
			(hide yes)
			(effects
				(font
					(size 0.7874 0.5842)
					(thickness 0.1524)
				)
				(justify mirror)
			)
		)
		(property "User Part Number" "PARTNUM*"
			(at -0.02032 4.024884 270)
			(unlocked yes)
			(layer "Cmts.User")
			(hide yes)
			(effects
				(font
					(size 0.7874 0.5842)
					(thickness 0.1524)
				)
				(justify mirror)
			)
		)
		(property "Device Type" "RESISTOR-G155-133R0-01,33OHM,1%"
			(at -0.008382 1.210564 270)
			(unlocked yes)
			(layer "B.Fab")
			(hide yes)
			(effects
				(font
					(size 0.7874 0.5842)
					(thickness 0.1524)
				)
				(justify mirror)
			)
		)
		(duplicate_pad_numbers_are_jumpers no)
		(fp_line
			(start -1.143 0.5588)
			(end -1.143 -0.5588)
			(stroke
				(width 0.1)
				(type default)
			)
			(layer "B.SilkS")
		)
		(fp_line
			(start 1.143 0.5588)
			(end -1.143 0.5588)
			(stroke
				(width 0.1)
				(type default)
			)
			(layer "B.SilkS")
		)
		(fp_line
			(start -1.143 -0.5588)
			(end 1.143 -0.5588)
			(stroke
				(width 0.1)
				(type default)
			)
			(layer "B.SilkS")
		)
		(fp_line
			(start 1.143 -0.5588)
			(end 1.143 0.5588)
			(stroke
				(width 0.1)
				(type default)
			)
			(layer "B.SilkS")
		)
		(fp_rect
			(start 1.143 0.5588)
			(end -1.143 -0.5588)
			(stroke
				(width 0)
				(type default)
			)
			(fill no)
			(layer "B.CrtYd")
		)
		(fp_line
			(start -0.508 0.3048)
			(end -0.508 -0.3048)
			(stroke
				(width 0.1)
				(type default)
			)
			(layer "B.Fab")
		)
		(fp_line
			(start 0.508 0.3048)
			(end -0.508 0.3048)
			(stroke
				(width 0.1)
				(type default)
			)
			(layer "B.Fab")
		)
		(fp_line
			(start -0.508 -0.3048)
			(end 0.508 -0.3048)
			(stroke
				(width 0.1)
				(type default)
			)
			(layer "B.Fab")
		)
		(fp_line
			(start 0.508 -0.3048)
			(end 0.508 0.3048)
			(stroke
				(width 0.1)
				(type default)
			)
			(layer "B.Fab")
		)
		(pad "1" smd rect
			(at 0.5334 0 90)
			(size 0.7112 0.6096)
			(layers "B.Cu" "B.Mask" "B.Paste")
			(net "FPGA_IN_GPSTP2_OUT")
		)
		(pad "2" smd rect
			(at -0.5334 0 90)
			(size 0.7112 0.6096)
			(layers "B.Cu" "B.Mask" "B.Paste")
			(net "GPSTP2_OUT")
		)
		(zone
			(layer "B.Cu")
			(hatch none 0.5)
			(connect_pads
				(clearance 0)
			)
			(min_thickness 0.25)
			(keepout
				(tracks allowed)
				(vias not_allowed)
				(pads allowed)
				(copperpour not_allowed)
				(footprints allowed)
			)
			(placement
				(enabled no)
				(sheetname "")
			)
			(fill
				(thermal_gap 0.5)
				(thermal_bridge_width 0.5)
				(island_removal_mode 0)
			)
			(polygon
				(pts
					(xy 123.7742 -89.4588) (xy 124.3838 -89.4588) (xy 124.3838 -89.6112) (xy 123.7742 -89.6112)
				)
			)
		)
	)
)
